# TIMECARD (Time Appliance Project (Time Card)) — schematic netlist excerpt (pin names and nets, part order shuffled) for the footprints in the layout excerpt that follows; sources: Cadence DE-HDL packaged netlist, KiCad conversion of R4006-B0001-02_R01.brd

R83  RESISTOR  0OHM -  pkg SMC_0402R_H016  page 21 : \1\ = FPGA_OUT_MAC_PPS_IN1P ; \2\ = R_MAC_PPS_IN1P
R234  RESISTOR  33OHM 1%  pkg SMC_0402R_H016  page 11 : \1\ = FPGA_D00_MOSI ; \2\ = FPGA_FLASH_DQ0_MOSI

(kicad_pcb
	(version 20260206)
	(generator "pcbnew")
	(generator_version "10.0")
	(general
		(thickness 1.6)
		(legacy_teardrops no)
	)
	(paper "A4")
	(title_block
		(title "timecard-production-celestica-r4006 — R4006-B0001-02_R01.brd")
		(comment 1 "Time Appliance Project (Time Card) / footprints 126-127 of 1113")
	)
	(layers
		(0 "F.Cu" signal "TOP")
		(4 "In1.Cu" signal "L02_GND1")
		(6 "In2.Cu" signal "L03_SIG1")
		(8 "In3.Cu" signal "L04_GND2")
		(10 "In4.Cu" signal "L05_VCC1")
		(12 "In5.Cu" signal "L06_VCC2")
		(14 "In6.Cu" signal "L07_GND3")
		(16 "In7.Cu" signal "L08_SIG2")
		(18 "In8.Cu" signal "L09_GND4")
		(2 "B.Cu" signal "BOTTOM")
		(9 "F.Adhes" user "F.Adhesive")
		(11 "B.Adhes" user "B.Adhesive")
		(13 "F.Paste" user "Package Geometry/Pastemask Top")
		(15 "B.Paste" user "Package Geometry/Pastemask Bottom")
		(5 "F.SilkS" user "Ref Des/Silkscreen Top")
		(7 "B.SilkS" user "Ref Des/Silkscreen Bottom")
		(1 "F.Mask" user "Board Geometry/Soldermask Top")
		(3 "B.Mask" user "Board Geometry/Soldermask Bottom")
		(17 "Dwgs.User" user "User.Drawings")
		(19 "Cmts.User" user "User.Comments")
		(21 "Eco1.User" user "User.Eco1")
		(23 "Eco2.User" user "User.Eco2")
		(25 "Edge.Cuts" user "Board Geometry/Outline")
		(27 "Margin" user)
		(31 "F.CrtYd" user "Package Geometry/Place Bound Top")
		(29 "B.CrtYd" user "Package Geometry/Place Bound Bottom")
		(35 "F.Fab" user "Ref Des/Assembly Top")
		(33 "B.Fab" user "Ref Des/Assembly Bottom")
	)
	(footprint ""
		(layer "F.Cu")
		(at 81.0006 -53.594 180)
		(property "Reference" "R83"
			(at 0.9906 -14.64437 0)
			(unlocked yes)
			(layer "F.SilkS")
			(effects
				(font
					(size 0.7874 0.5842)
					(thickness 0.1524)
				)
			)
		)
		(property "Value" "VAL*"
			(at 0.02032 2.13233 180)
			(unlocked yes)
			(layer "F.Fab")
			(hide yes)
			(effects
				(font
					(size 0.7874 0.5842)
					(thickness 0.1524)
				)
			)
		)
		(property "Device Type" "RESISTOR-G155-100R0-J0,0OHM,-"
			(at 0.008382 1.210564 180)
			(unlocked yes)
			(layer "F.Fab")
			(hide yes)
			(effects
				(font
					(size 0.7874 0.5842)
					(thickness 0.1524)
				)
			)
		)
		(property "User Part Number" "PARTNUM*"
			(at 0.02032 4.024884 180)
			(unlocked yes)
			(layer "Cmts.User")
			(hide yes)
			(effects
				(font
					(size 0.7874 0.5842)
					(thickness 0.1524)
				)
			)
		)
		(property "Tolerance" "TOL*"
			(at 0.044704 3.05435 180)
			(unlocked yes)
			(layer "Cmts.User")
			(hide yes)
			(effects
				(font
					(size 0.7874 0.5842)
					(thickness 0.1524)
				)
			)
		)
		(duplicate_pad_numbers_are_jumpers no)
		(fp_line
			(start 1.143 0.5588)
			(end 1.143 -0.5588)
			(stroke
				(width 0.1)
				(type default)
			)
			(layer "F.SilkS")
		)
		(fp_line
			(start 1.143 -0.5588)
			(end -1.143 -0.5588)
			(stroke
				(width 0.1)
				(type default)
			)
			(layer "F.SilkS")
		)
		(fp_line
			(start -1.143 0.5588)
			(end 1.143 0.5588)
			(stroke
				(width 0.1)
				(type default)
			)
			(layer "F.SilkS")
		)
		(fp_line
			(start -1.143 -0.5588)
			(end -1.143 0.5588)
			(stroke
				(width 0.1)
				(type default)
			)
			(layer "F.SilkS")
		)
		(fp_rect
			(start 1.143 -0.5588)
			(end -1.143 0.5588)
			(stroke
				(width 0)
				(type default)
			)
			(fill no)
			(layer "F.CrtYd")
		)
		(fp_line
			(start 0.508 0.3048)
			(end 0.508 -0.3048)
			(stroke
				(width 0.1)
				(type default)
			)
			(layer "F.Fab")
		)
		(fp_line
			(start 0.508 -0.3048)
			(end -0.508 -0.3048)
			(stroke
				(width 0.1)
				(type default)
			)
			(layer "F.Fab")
		)
		(fp_line
			(start -0.508 0.3048)
			(end 0.508 0.3048)
			(stroke
				(width 0.1)
				(type default)
			)
			(layer "F.Fab")
		)
		(fp_line
			(start -0.508 -0.3048)
			(end -0.508 0.3048)
			(stroke
				(width 0.1)
				(type default)
			)
			(layer "F.Fab")
		)
		(pad "1" smd rect
			(at -0.5334 0 180)
			(size 0.7112 0.6096)
			(layers "F.Cu" "F.Mask" "F.Paste")
			(net "FPGA_OUT_MAC_PPS_IN1P")
		)
		(pad "2" smd rect
			(at 0.5334 0 180)
			(size 0.7112 0.6096)
			(layers "F.Cu" "F.Mask" "F.Paste")
			(net "R_MAC_PPS_IN1P")
		)
		(zone
			(layer "F.Cu")
			(hatch none 0.5)
			(connect_pads
				(clearance 0)
			)
			(min_thickness 0.25)
			(keepout
				(tracks allowed)
				(vias not_allowed)
				(pads allowed)
				(copperpour not_allowed)
				(footprints allowed)
			)
			(placement
				(enabled no)
				(sheetname "")
			)
			(fill
				(thermal_gap 0.5)
				(thermal_bridge_width 0.5)
				(island_removal_mode 0)
			)
			(polygon
				(pts
					(xy 80.9244 -53.2892) (xy 81.0768 -53.2892) (xy 81.0768 -53.8988) (xy 80.9244 -53.8988)
				)
			)
		)
	)
	(footprint ""
		(layer "F.Cu")
		(at 113.919 -61.976 90)
		(property "Reference" "R234"
			(at 3.302 0.29337 90)
			(unlocked yes)
			(layer "F.SilkS")
			(effects
				(font
					(size 0.7874 0.5842)
					(thickness 0.1524)
				)
			)
		)
		(property "Value" "VAL*"
			(at 0.02032 2.13233 90)
			(unlocked yes)
			(layer "F.Fab")
			(hide yes)
			(effects
				(font
					(size 0.7874 0.5842)
					(thickness 0.1524)
				)
			)
		)
		(property "Tolerance" "TOL*"
			(at 0.044704 3.05435 90)
			(unlocked yes)
			(layer "Cmts.User")
			(hide yes)
			(effects
				(font
					(size 0.7874 0.5842)
					(thickness 0.1524)
				)
			)
		)
		(property "User Part Number" "PARTNUM*"
			(at 0.02032 4.024884 90)
			(unlocked yes)
			(layer "Cmts.User")
			(hide yes)
			(effects
				(font
					(size 0.7874 0.5842)
					(thickness 0.1524)
				)
			)
		)
		(property "Device Type" "RESISTOR-G155-133R0-01,33OHM,1%"
			(at 0.008382 1.210564 90)
			(unlocked yes)
			(layer "F.Fab")
			(hide yes)
			(effects
				(font
					(size 0.7874 0.5842)
					(thickness 0.1524)
				)
			)
		)
		(duplicate_pad_numbers_are_jumpers no)
		(fp_line
			(start 1.143 -0.5588)
			(end -1.143 -0.5588)
			(stroke
				(width 0.1)
				(type default)
			)
			(layer "F.SilkS")
		)
		(fp_line
			(start -1.143 -0.5588)
			(end -1.143 0.5588)
			(stroke
				(width 0.1)
				(type default)
			)
			(layer "F.SilkS")
		)
		(fp_line
			(start 1.143 0.5588)
			(end 1.143 -0.5588)
			(stroke
				(width 0.1)
				(type default)
			)
			(layer "F.SilkS")
		)
		(fp_line
			(start -1.143 0.5588)
			(end 1.143 0.5588)
			(stroke
				(width 0.1)
				(type default)
			)
			(layer "F.SilkS")
		)
		(fp_poly
			(pts
				(xy -1.143 0.5588) (xy 1.143 0.5588) (xy 1.143 -0.5588) (xy -1.143 -0.5588)
			)
			(stroke
				(width 0)
				(type default)
			)
			(fill no)
			(layer "F.CrtYd")
		)
		(fp_line
			(start 0.508 -0.3048)
			(end -0.508 -0.3048)
			(stroke
				(width 0.1)
				(type default)
			)
			(layer "F.Fab")
		)
		(fp_line
			(start -0.508 -0.3048)
			(end -0.508 0.3048)
			(stroke
				(width 0.1)
				(type default)
			)
			(layer "F.Fab")
		)
		(fp_line
			(start 0.508 0.3048)
			(end 0.508 -0.3048)
			(stroke
				(width 0.1)
				(type default)
			)
			(layer "F.Fab")
		)
		(fp_line
			(start -0.508 0.3048)
			(end 0.508 0.3048)
			(stroke
				(width 0.1)
				(type default)
			)
			(layer "F.Fab")
		)
		(pad "1" smd rect
			(at -0.5334 0 90)
			(size 0.7112 0.6096)
			(layers "F.Cu" "F.Mask" "F.Paste")
			(net "FPGA_D00_MOSI")
		)
		(pad "2" smd rect
			(at 0.5334 0 90)
			(size 0.7112 0.6096)
			(layers "F.Cu" "F.Mask" "F.Paste")
			(net "FPGA_FLASH_DQ0_MOSI")
		)
		(zone
			(layer "F.Cu")
			(hatch none 0.5)
			(connect_pads
				(clearance 0)
			)
			(min_thickness 0.25)
			(keepout
				(tracks allowed)
				(vias not_allowed)
				(pads allowed)
				(copperpour not_allowed)
				(footprints allowed)
			)
			(placement
				(enabled no)
				(sheetname "")
			)
			(fill
				(thermal_gap 0.5)
				(thermal_bridge_width 0.5)
				(island_removal_mode 0)
			)
			(polygon
				(pts
					(xy 114.2238 -61.8998) (xy 114.2238 -62.0522) (xy 113.6142 -62.0522) (xy 113.6142 -61.8998)
				)
			)
		)
		(zone
			(layer "F.Cu")
			(hatch none 0.5)
			(connect_pads
				(clearance 0)
			)
			(min_thickness 0.25)
			(keepout
				(tracks not_allowed)
				(vias allowed)
				(pads allowed)
				(copperpour not_allowed)
				(footprints allowed)
			)
			(placement
				(enabled no)
				(sheetname "")
			)
			(fill
				(thermal_gap 0.5)
				(thermal_bridge_width 0.5)
				(island_removal_mode 0)
			)
			(polygon
				(pts
					(xy 114.2238 -61.8998) (xy 114.2238 -62.0522) (xy 113.6142 -62.0522) (xy 113.6142 -61.8998)
				)
			)
		)
	)
)
